# S9S_MB_2U (Grand Teton) — schematic netlist excerpt (pin names and nets, part order shuffled) for the footprints in the layout excerpt that follows; sources: Cadence DE-HDL packaged netlist, KiCad conversion of 03242023_DA0F0TMBIJ0_F0T_Motherboard_J_brd_V01_OCP.brd

PR2537  Q_RES  10 1% EMPTY  pkg 0402LF  page 304 : A = P12V_AUX ; B = P12V_HSC_GATE_RC
R707  Q_RES  10K 1% EMPTY  pkg 0402LF  page 129 : A = RST_PLD_CPU0_DRAM_CD_N ; B = GND

(kicad_pcb
	(version 20260206)
	(generator "pcbnew")
	(generator_version "10.0")
	(general
		(thickness 1.6)
		(legacy_teardrops no)
	)
	(paper "A4")
	(title_block
		(title "03242023_DA0F0TMBIJ0_F0T_Motherboard_J_brd_V01_OCP.brd")
		(comment 1 "Grand Teton / footprints 5608-5609 of 6105")
	)
	(layers
		(0 "F.Cu" signal "TOP")
		(4 "In1.Cu" signal "GND")
		(6 "In2.Cu" signal "IN1")
		(8 "In3.Cu" signal "GND1")
		(10 "In4.Cu" signal "IN2")
		(12 "In5.Cu" signal "GND2")
		(14 "In6.Cu" signal "IN3")
		(16 "In7.Cu" signal "GND3")
		(18 "In8.Cu" signal "VCC")
		(20 "In9.Cu" signal "VCC1")
		(22 "In10.Cu" signal "GND4")
		(24 "In11.Cu" signal "IN4")
		(26 "In12.Cu" signal "GND5")
		(28 "In13.Cu" signal "IN5")
		(30 "In14.Cu" signal "GND6")
		(32 "In15.Cu" signal "IN6")
		(34 "In16.Cu" signal "GND7")
		(2 "B.Cu" signal "BOTTOM")
		(9 "F.Adhes" user "F.Adhesive")
		(11 "B.Adhes" user "B.Adhesive")
		(13 "F.Paste" user "Package Geometry/Pastemask Top")
		(15 "B.Paste" user "Package Geometry/Pastemask Bottom")
		(5 "F.SilkS" user "Ref Des/Silkscreen Top")
		(7 "B.SilkS" user "Ref Des/Silkscreen Bottom")
		(1 "F.Mask" user "Board Geometry/Soldermask Top")
		(3 "B.Mask" user "Board Geometry/Soldermask Bottom")
		(17 "Dwgs.User" user "User.Drawings")
		(19 "Cmts.User" user "User.Comments")
		(21 "Eco1.User" user "User.Eco1")
		(23 "Eco2.User" user "User.Eco2")
		(25 "Edge.Cuts" user "Board Geometry/Outline")
		(27 "Margin" user)
		(31 "F.CrtYd" user "Package Geometry/Place Bound Top")
		(29 "B.CrtYd" user "Package Geometry/Place Bound Bottom")
		(35 "F.Fab" user "Ref Des/Assembly Top")
		(33 "B.Fab" user "Ref Des/Assembly Bottom")
	)
	(footprint ""
		(layer "B.Cu")
		(at 267.652246 -193.503296 -90)
		(property "Reference" "R707"
			(at 0 0 90)
			(layer "B.SilkS")
			(hide yes)
			(effects
				(font
					(size 1.27 1.27)
				)
				(justify mirror)
			)
		)
		(property "Value" ""
			(at 0 0 90)
			(layer "B.Fab")
			(effects
				(font
					(size 1.27 1.27)
				)
				(justify mirror)
			)
		)
		(duplicate_pad_numbers_are_jumpers no)
		(fp_line
			(start -0.7874 0.4064)
			(end 0.7874 0.4064)
			(stroke
				(width 0.1524)
				(type default)
			)
			(layer "B.SilkS")
		)
		(fp_line
			(start 0.7874 0.4064)
			(end 0.7874 -0.4064)
			(stroke
				(width 0.1524)
				(type default)
			)
			(layer "B.SilkS")
		)
		(fp_line
			(start -0.7874 -0.4064)
			(end -0.7874 0.4064)
			(stroke
				(width 0.1524)
				(type default)
			)
			(layer "B.SilkS")
		)
		(fp_line
			(start 0.7874 -0.4064)
			(end -0.7874 -0.4064)
			(stroke
				(width 0.1524)
				(type default)
			)
			(layer "B.SilkS")
		)
		(fp_line
			(start -0.67945 0.3048)
			(end -0.120396 0.3048)
			(stroke
				(width 0.1)
				(type default)
			)
			(layer "B.Fab")
		)
		(fp_line
			(start -0.120396 0.3048)
			(end -0.120396 0.2794)
			(stroke
				(width 0.1)
				(type default)
			)
			(layer "B.Fab")
		)
		(fp_line
			(start 0.12065 0.3048)
			(end 0.67945 0.3048)
			(stroke
				(width 0.1)
				(type default)
			)
			(layer "B.Fab")
		)
		(fp_line
			(start 0.67945 0.3048)
			(end 0.67945 -0.305054)
			(stroke
				(width 0.1)
				(type default)
			)
			(layer "B.Fab")
		)
		(fp_line
			(start -0.120396 0.2794)
			(end 0.12065 0.2794)
			(stroke
				(width 0.1)
				(type default)
			)
			(layer "B.Fab")
		)
		(fp_line
			(start 0.12065 0.2794)
			(end 0.12065 0.3048)
			(stroke
				(width 0.1)
				(type default)
			)
			(layer "B.Fab")
		)
		(fp_line
			(start -0.12065 -0.2794)
			(end -0.12065 -0.3048)
			(stroke
				(width 0.1)
				(type default)
			)
			(layer "B.Fab")
		)
		(fp_line
			(start 0.12065 -0.2794)
			(end -0.12065 -0.2794)
			(stroke
				(width 0.1)
				(type default)
			)
			(layer "B.Fab")
		)
		(fp_line
			(start -0.67945 -0.3048)
			(end -0.67945 0.3048)
			(stroke
				(width 0.1)
				(type default)
			)
			(layer "B.Fab")
		)
		(fp_line
			(start -0.12065 -0.3048)
			(end -0.67945 -0.3048)
			(stroke
				(width 0.1)
				(type default)
			)
			(layer "B.Fab")
		)
		(fp_line
			(start 0.12065 -0.305054)
			(end 0.12065 -0.2794)
			(stroke
				(width 0.1)
				(type default)
			)
			(layer "B.Fab")
		)
		(fp_line
			(start 0.67945 -0.305054)
			(end 0.12065 -0.305054)
			(stroke
				(width 0.1)
				(type default)
			)
			(layer "B.Fab")
		)
		(pad "1" smd circle
			(at 0.40005 0 90)
			(size 0 0)
			(layers "B.Cu" "B.Mask" "B.Paste")
			(net "RST_PLD_CPU0_DRAM_CD_N")
		)
		(pad "2" smd circle
			(at -0.40005 0 90)
			(size 0 0)
			(layers "B.Cu" "B.Mask" "B.Paste")
			(net "GND")
		)
	)
	(footprint ""
		(layer "B.Cu")
		(at 243.496084 -397.067024 180)
		(property "Reference" "PR2537"
			(at 0 0 0)
			(layer "B.SilkS")
			(hide yes)
			(effects
				(font
					(size 1.27 1.27)
				)
				(justify mirror)
			)
		)
		(property "Value" ""
			(at 0 0 0)
			(layer "B.Fab")
			(effects
				(font
					(size 1.27 1.27)
				)
				(justify mirror)
			)
		)
		(duplicate_pad_numbers_are_jumpers no)
		(fp_line
			(start 0.7874 0.4064)
			(end 0.7874 -0.4064)
			(stroke
				(width 0.1524)
				(type default)
			)
			(layer "B.SilkS")
		)
		(fp_line
			(start 0.7874 -0.4064)
			(end -0.7874 -0.4064)
			(stroke
				(width 0.1524)
				(type default)
			)
			(layer "B.SilkS")
		)
		(fp_line
			(start -0.7874 0.4064)
			(end 0.7874 0.4064)
			(stroke
				(width 0.1524)
				(type default)
			)
			(layer "B.SilkS")
		)
		(fp_line
			(start -0.7874 -0.4064)
			(end -0.7874 0.4064)
			(stroke
				(width 0.1524)
				(type default)
			)
			(layer "B.SilkS")
		)
		(fp_line
			(start 0.67945 0.3048)
			(end 0.67945 -0.305054)
			(stroke
				(width 0.1)
				(type default)
			)
			(layer "B.Fab")
		)
		(fp_line
			(start 0.67945 -0.305054)
			(end 0.12065 -0.305054)
			(stroke
				(width 0.1)
				(type default)
			)
			(layer "B.Fab")
		)
		(fp_line
			(start 0.12065 0.3048)
			(end 0.67945 0.3048)
			(stroke
				(width 0.1)
				(type default)
			)
			(layer "B.Fab")
		)
		(fp_line
			(start 0.12065 0.2794)
			(end 0.12065 0.3048)
			(stroke
				(width 0.1)
				(type default)
			)
			(layer "B.Fab")
		)
		(fp_line
			(start 0.12065 -0.2794)
			(end -0.12065 -0.2794)
			(stroke
				(width 0.1)
				(type default)
			)
			(layer "B.Fab")
		)
		(fp_line
			(start 0.12065 -0.305054)
			(end 0.12065 -0.2794)
			(stroke
				(width 0.1)
				(type default)
			)
			(layer "B.Fab")
		)
		(fp_line
			(start -0.120396 0.3048)
			(end -0.120396 0.2794)
			(stroke
				(width 0.1)
				(type default)
			)
			(layer "B.Fab")
		)
		(fp_line
			(start -0.120396 0.2794)
			(end 0.12065 0.2794)
			(stroke
				(width 0.1)
				(type default)
			)
			(layer "B.Fab")
		)
		(fp_line
			(start -0.12065 -0.2794)
			(end -0.12065 -0.3048)
			(stroke
				(width 0.1)
				(type default)
			)
			(layer "B.Fab")
		)
		(fp_line
			(start -0.12065 -0.3048)
			(end -0.67945 -0.3048)
			(stroke
				(width 0.1)
				(type default)
			)
			(layer "B.Fab")
		)
		(fp_line
			(start -0.67945 0.3048)
			(end -0.120396 0.3048)
			(stroke
				(width 0.1)
				(type default)
			)
			(layer "B.Fab")
		)
		(fp_line
			(start -0.67945 -0.3048)
			(end -0.67945 0.3048)
			(stroke
				(width 0.1)
				(type default)
			)
			(layer "B.Fab")
		)
		(pad "1" smd circle
			(at 0.40005 0)
			(size 0 0)
			(layers "B.Cu" "B.Mask" "B.Paste")
			(net "P12V_AUX")
		)
		(pad "2" smd circle
			(at -0.40005 0)
			(size 0 0)
			(layers "B.Cu" "B.Mask" "B.Paste")
			(net "P12V_HSC_GATE_RC")
		)
	)
)
